(kicad_pcb
	(version 20260206)
	(generator "pcbnew")
	(generator_version "10.0")
	(general
		(thickness 1.6)
		(legacy_teardrops no)
	)
	(paper "A4")
	(title_block
		(title "03242023_DA0F0TMBIJ0_F0T_Motherboard_J_brd_V01_OCP.brd")
		(comment 1 "Grand Teton / footprint 1660 of 6105 (J24), pads 113-224 of 291")
	)
	(layers
		(0 "F.Cu" signal "TOP")
		(4 "In1.Cu" signal "GND")
		(6 "In2.Cu" signal "IN1")
		(8 "In3.Cu" signal "GND1")
		(10 "In4.Cu" signal "IN2")
		(12 "In5.Cu" signal "GND2")
		(14 "In6.Cu" signal "IN3")
		(16 "In7.Cu" signal "GND3")
		(18 "In8.Cu" signal "VCC")
		(20 "In9.Cu" signal "VCC1")
		(22 "In10.Cu" signal "GND4")
		(24 "In11.Cu" signal "IN4")
		(26 "In12.Cu" signal "GND5")
		(28 "In13.Cu" signal "IN5")
		(30 "In14.Cu" signal "GND6")
		(32 "In15.Cu" signal "IN6")
		(34 "In16.Cu" signal "GND7")
		(2 "B.Cu" signal "BOTTOM")
		(9 "F.Adhes" user "F.Adhesive")
		(11 "B.Adhes" user "B.Adhesive")
		(13 "F.Paste" user "Package Geometry/Pastemask Top")
		(15 "B.Paste" user "Package Geometry/Pastemask Bottom")
		(5 "F.SilkS" user "Ref Des/Silkscreen Top")
		(7 "B.SilkS" user "Ref Des/Silkscreen Bottom")
		(1 "F.Mask" user "Board Geometry/Soldermask Top")
		(3 "B.Mask" user "Board Geometry/Soldermask Bottom")
		(17 "Dwgs.User" user "User.Drawings")
		(19 "Cmts.User" user "User.Comments")
		(21 "Eco1.User" user "User.Eco1")
		(23 "Eco2.User" user "User.Eco2")
		(25 "Edge.Cuts" user "Board Geometry/Outline")
		(27 "Margin" user)
		(31 "F.CrtYd" user "Package Geometry/Place Bound Top")
		(29 "B.CrtYd" user "Package Geometry/Place Bound Bottom")
		(35 "F.Fab" user "Ref Des/Assembly Top")
		(33 "B.Fab" user "Ref Des/Assembly Bottom")
	)
	(footprint ""
		(layer "F.Cu")
		(at 17.73428 -258.091686)
		(property "Reference" "J24"
			(at -3.0607 -81.901792 0)
			(unlocked yes)
			(layer "F.SilkS")
			(effects
				(font
					(size 0.7874 0.5842)
					(thickness 0.1524)
				)
				(justify left)
			)
		)
		(property "Value" ""
			(at 0 0 0)
			(layer "F.Fab")
			(effects
				(font
					(size 1.27 1.27)
				)
			)
		)
		(duplicate_pad_numbers_are_jumpers no)
		(pad "113" smd rect
			(at -2.050034 36.975034 270)
			(size 0.519938 1.4986)
			(layers "F.Cu" "F.Mask" "F.Paste")
			(net "M_D_CPU1_SB_DQ<9>")
		)
		(pad "114" smd rect
			(at -2.050034 37.824918 270)
			(size 0.519938 1.4986)
			(layers "F.Cu" "F.Mask" "F.Paste")
			(net "GND")
		)
		(pad "115" smd rect
			(at -2.050034 38.675056 270)
			(size 0.519938 1.4986)
			(layers "F.Cu" "F.Mask" "F.Paste")
			(net "M_D_CPU1_SB_DQS_DP<1>")
		)
		(pad "116" smd rect
			(at -2.050034 39.52494 270)
			(size 0.519938 1.4986)
			(layers "F.Cu" "F.Mask" "F.Paste")
			(net "M_D_CPU1_SB_DQS_DN<1>")
		)
		(pad "117" smd rect
			(at -2.050034 40.375078 270)
			(size 0.519938 1.4986)
			(layers "F.Cu" "F.Mask" "F.Paste")
			(net "GND")
		)
		(pad "118" smd rect
			(at -2.050034 41.224962 270)
			(size 0.519938 1.4986)
			(layers "F.Cu" "F.Mask" "F.Paste")
			(net "M_D_CPU1_SB_DQ<12>")
		)
		(pad "119" smd rect
			(at -2.050034 42.0751 270)
			(size 0.519938 1.4986)
			(layers "F.Cu" "F.Mask" "F.Paste")
			(net "GND")
		)
		(pad "120" smd rect
			(at -2.050034 42.924984 270)
			(size 0.519938 1.4986)
			(layers "F.Cu" "F.Mask" "F.Paste")
			(net "M_D_CPU1_SB_DQ<13>")
		)
		(pad "121" smd rect
			(at -2.050034 43.775122 270)
			(size 0.519938 1.4986)
			(layers "F.Cu" "F.Mask" "F.Paste")
			(net "GND")
		)
		(pad "122" smd rect
			(at -2.050034 44.625006 270)
			(size 0.519938 1.4986)
			(layers "F.Cu" "F.Mask" "F.Paste")
			(net "M_D_CPU1_SB_DQ<16>")
		)
		(pad "123" smd rect
			(at -2.050034 45.47489 270)
			(size 0.519938 1.4986)
			(layers "F.Cu" "F.Mask" "F.Paste")
			(net "GND")
		)
		(pad "124" smd rect
			(at -2.050034 46.325028 270)
			(size 0.519938 1.4986)
			(layers "F.Cu" "F.Mask" "F.Paste")
			(net "M_D_CPU1_SB_DQ<17>")
		)
		(pad "125" smd rect
			(at -2.050034 47.174912 270)
			(size 0.519938 1.4986)
			(layers "F.Cu" "F.Mask" "F.Paste")
			(net "GND")
		)
		(pad "126" smd rect
			(at -2.050034 48.02505 270)
			(size 0.519938 1.4986)
			(layers "F.Cu" "F.Mask" "F.Paste")
			(net "M_D_CPU1_SB_DQS_DP<2>")
		)
		(pad "127" smd rect
			(at -2.050034 48.874934 270)
			(size 0.519938 1.4986)
			(layers "F.Cu" "F.Mask" "F.Paste")
			(net "M_D_CPU1_SB_DQS_DN<2>")
		)
		(pad "128" smd rect
			(at -2.050034 49.725072 270)
			(size 0.519938 1.4986)
			(layers "F.Cu" "F.Mask" "F.Paste")
			(net "GND")
		)
		(pad "129" smd rect
			(at -2.050034 50.574956 270)
			(size 0.519938 1.4986)
			(layers "F.Cu" "F.Mask" "F.Paste")
			(net "M_D_CPU1_SB_DQ<20>")
		)
		(pad "130" smd rect
			(at -2.050034 51.425094 270)
			(size 0.519938 1.4986)
			(layers "F.Cu" "F.Mask" "F.Paste")
			(net "GND")
		)
		(pad "131" smd rect
			(at -2.050034 52.274978 270)
			(size 0.519938 1.4986)
			(layers "F.Cu" "F.Mask" "F.Paste")
			(net "M_D_CPU1_SB_DQ<21>")
		)
		(pad "132" smd rect
			(at -2.050034 53.125116 270)
			(size 0.519938 1.4986)
			(layers "F.Cu" "F.Mask" "F.Paste")
			(net "GND")
		)
		(pad "133" smd rect
			(at -2.050034 53.975 270)
			(size 0.519938 1.4986)
			(layers "F.Cu" "F.Mask" "F.Paste")
			(net "M_D_CPU1_SB_DQ<24>")
		)
		(pad "134" smd rect
			(at -2.050034 54.824884 270)
			(size 0.519938 1.4986)
			(layers "F.Cu" "F.Mask" "F.Paste")
			(net "GND")
		)
		(pad "135" smd rect
			(at -2.050034 55.675022 270)
			(size 0.519938 1.4986)
			(layers "F.Cu" "F.Mask" "F.Paste")
			(net "M_D_CPU1_SB_DQ<25>")
		)
		(pad "136" smd rect
			(at -2.050034 56.524906 270)
			(size 0.519938 1.4986)
			(layers "F.Cu" "F.Mask" "F.Paste")
			(net "GND")
		)
		(pad "137" smd rect
			(at -2.050034 57.375044 270)
			(size 0.519938 1.4986)
			(layers "F.Cu" "F.Mask" "F.Paste")
			(net "M_D_CPU1_SB_DQS_DP<3>")
		)
		(pad "138" smd rect
			(at -2.050034 58.224928 270)
			(size 0.519938 1.4986)
			(layers "F.Cu" "F.Mask" "F.Paste")
			(net "M_D_CPU1_SB_DQS_DN<3>")
		)
		(pad "139" smd rect
			(at -2.050034 59.075066 270)
			(size 0.519938 1.4986)
			(layers "F.Cu" "F.Mask" "F.Paste")
			(net "GND")
		)
		(pad "140" smd rect
			(at -2.050034 59.92495 270)
			(size 0.519938 1.4986)
			(layers "F.Cu" "F.Mask" "F.Paste")
			(net "M_D_CPU1_SB_DQ<28>")
		)
		(pad "141" smd rect
			(at -2.050034 60.775088 270)
			(size 0.519938 1.4986)
			(layers "F.Cu" "F.Mask" "F.Paste")
			(net "GND")
		)
		(pad "142" smd rect
			(at -2.050034 61.624972 270)
			(size 0.519938 1.4986)
			(layers "F.Cu" "F.Mask" "F.Paste")
			(net "M_D_CPU1_SB_DQ<29>")
		)
		(pad "143" smd rect
			(at -2.050034 62.47511 270)
			(size 0.519938 1.4986)
			(layers "F.Cu" "F.Mask" "F.Paste")
			(net "GND")
		)
		(pad "144" smd rect
			(at -2.050034 63.324994 270)
			(size 0.519938 1.4986)
			(layers "F.Cu" "F.Mask" "F.Paste")
			(net "TP_CHD_CPU1_DIMM2_FRU_1")
		)
		(pad "145" smd rect
			(at 2.050034 -63.324994 270)
			(size 0.519938 1.4986)
			(layers "F.Cu" "F.Mask" "F.Paste")
			(net "P12V_S3_AUX_CPU1_NVDIMM")
		)
		(pad "146" smd rect
			(at 2.050034 -62.47511 270)
			(size 0.519938 1.4986)
			(layers "F.Cu" "F.Mask" "F.Paste")
			(net "P12V_S3_AUX_CPU1_NVDIMM")
		)
		(pad "147" smd rect
			(at 2.050034 -61.624972 270)
			(size 0.519938 1.4986)
			(layers "F.Cu" "F.Mask" "F.Paste")
			(net "PWRGD_CHD_CPU1_DIMM2")
		)
		(pad "148" smd rect
			(at 2.050034 -60.775088 270)
			(size 0.519938 1.4986)
			(layers "F.Cu" "F.Mask" "F.Paste")
			(net "PD_CHD_CPU1_DIMM2_SAA")
		)
		(pad "149" smd rect
			(at 2.050034 -59.92495 270)
			(size 0.519938 1.4986)
			(layers "F.Cu" "F.Mask" "F.Paste")
			(net "TP_CHD_CPU1_DIMM2_FRU_2")
		)
		(pad "150" smd rect
			(at 2.050034 -59.075066 270)
			(size 0.519938 1.4986)
			(layers "F.Cu" "F.Mask" "F.Paste")
			(net "TP_CHD_CPU1_DIMM2_FRU_3")
		)
		(pad "151" smd rect
			(at 2.050034 -58.224928 270)
			(size 0.519938 1.4986)
			(layers "F.Cu" "F.Mask" "F.Paste")
			(net "GND")
		)
		(pad "152" smd rect
			(at 2.050034 -57.375044 270)
			(size 0.519938 1.4986)
			(layers "F.Cu" "F.Mask" "F.Paste")
			(net "M_D_CPU1_SA_DQ<2>")
		)
		(pad "153" smd rect
			(at 2.050034 -56.524906 270)
			(size 0.519938 1.4986)
			(layers "F.Cu" "F.Mask" "F.Paste")
			(net "GND")
		)
		(pad "154" smd rect
			(at 2.050034 -55.675022 270)
			(size 0.519938 1.4986)
			(layers "F.Cu" "F.Mask" "F.Paste")
			(net "M_D_CPU1_SA_DQ<3>")
		)
		(pad "155" smd rect
			(at 2.050034 -54.824884 270)
			(size 0.519938 1.4986)
			(layers "F.Cu" "F.Mask" "F.Paste")
			(net "GND")
		)
		(pad "156" smd rect
			(at 2.050034 -53.975 270)
			(size 0.519938 1.4986)
			(layers "F.Cu" "F.Mask" "F.Paste")
			(net "M_D_CPU1_SA_DQS_DN<5>")
		)
		(pad "157" smd rect
			(at 2.050034 -53.125116 270)
			(size 0.519938 1.4986)
			(layers "F.Cu" "F.Mask" "F.Paste")
			(net "M_D_CPU1_SA_DQS_DP<5>")
		)
		(pad "158" smd rect
			(at 2.050034 -52.274978 270)
			(size 0.519938 1.4986)
			(layers "F.Cu" "F.Mask" "F.Paste")
			(net "GND")
		)
		(pad "159" smd rect
			(at 2.050034 -51.425094 270)
			(size 0.519938 1.4986)
			(layers "F.Cu" "F.Mask" "F.Paste")
			(net "M_D_CPU1_SA_DQ<6>")
		)
		(pad "160" smd rect
			(at 2.050034 -50.574956 270)
			(size 0.519938 1.4986)
			(layers "F.Cu" "F.Mask" "F.Paste")
			(net "GND")
		)
		(pad "161" smd rect
			(at 2.050034 -49.725072 270)
			(size 0.519938 1.4986)
			(layers "F.Cu" "F.Mask" "F.Paste")
			(net "M_D_CPU1_SA_DQ<7>")
		)
		(pad "162" smd rect
			(at 2.050034 -48.874934 270)
			(size 0.519938 1.4986)
			(layers "F.Cu" "F.Mask" "F.Paste")
			(net "GND")
		)
		(pad "163" smd rect
			(at 2.050034 -48.02505 270)
			(size 0.519938 1.4986)
			(layers "F.Cu" "F.Mask" "F.Paste")
			(net "M_D_CPU1_SA_DQ<10>")
		)
		(pad "164" smd rect
			(at 2.050034 -47.174912 270)
			(size 0.519938 1.4986)
			(layers "F.Cu" "F.Mask" "F.Paste")
			(net "GND")
		)
		(pad "165" smd rect
			(at 2.050034 -46.325028 270)
			(size 0.519938 1.4986)
			(layers "F.Cu" "F.Mask" "F.Paste")
			(net "M_D_CPU1_SA_DQ<11>")
		)
		(pad "166" smd rect
			(at 2.050034 -45.47489 270)
			(size 0.519938 1.4986)
			(layers "F.Cu" "F.Mask" "F.Paste")
			(net "GND")
		)
		(pad "167" smd rect
			(at 2.050034 -44.625006 270)
			(size 0.519938 1.4986)
			(layers "F.Cu" "F.Mask" "F.Paste")
			(net "M_D_CPU1_SA_DQS_DN<6>")
		)
		(pad "168" smd rect
			(at 2.050034 -43.775122 270)
			(size 0.519938 1.4986)
			(layers "F.Cu" "F.Mask" "F.Paste")
			(net "M_D_CPU1_SA_DQS_DP<6>")
		)
		(pad "169" smd rect
			(at 2.050034 -42.924984 270)
			(size 0.519938 1.4986)
			(layers "F.Cu" "F.Mask" "F.Paste")
			(net "GND")
		)
		(pad "170" smd rect
			(at 2.050034 -42.0751 270)
			(size 0.519938 1.4986)
			(layers "F.Cu" "F.Mask" "F.Paste")
			(net "M_D_CPU1_SA_DQ<14>")
		)
		(pad "171" smd rect
			(at 2.050034 -41.224962 270)
			(size 0.519938 1.4986)
			(layers "F.Cu" "F.Mask" "F.Paste")
			(net "GND")
		)
		(pad "172" smd rect
			(at 2.050034 -40.375078 270)
			(size 0.519938 1.4986)
			(layers "F.Cu" "F.Mask" "F.Paste")
			(net "M_D_CPU1_SA_DQ<15>")
		)
		(pad "173" smd rect
			(at 2.050034 -39.52494 270)
			(size 0.519938 1.4986)
			(layers "F.Cu" "F.Mask" "F.Paste")
			(net "GND")
		)
		(pad "174" smd rect
			(at 2.050034 -38.675056 270)
			(size 0.519938 1.4986)
			(layers "F.Cu" "F.Mask" "F.Paste")
			(net "M_D_CPU1_SA_DQ<18>")
		)
		(pad "175" smd rect
			(at 2.050034 -37.824918 270)
			(size 0.519938 1.4986)
			(layers "F.Cu" "F.Mask" "F.Paste")
			(net "GND")
		)
		(pad "176" smd rect
			(at 2.050034 -36.975034 270)
			(size 0.519938 1.4986)
			(layers "F.Cu" "F.Mask" "F.Paste")
			(net "M_D_CPU1_SA_DQ<19>")
		)
		(pad "177" smd rect
			(at 2.050034 -36.124896 270)
			(size 0.519938 1.4986)
			(layers "F.Cu" "F.Mask" "F.Paste")
			(net "GND")
		)
		(pad "178" smd rect
			(at 2.050034 -35.275012 270)
			(size 0.519938 1.4986)
			(layers "F.Cu" "F.Mask" "F.Paste")
			(net "M_D_CPU1_SA_DQS_DN<7>")
		)
		(pad "179" smd rect
			(at 2.050034 -34.425128 270)
			(size 0.519938 1.4986)
			(layers "F.Cu" "F.Mask" "F.Paste")
			(net "M_D_CPU1_SA_DQS_DP<7>")
		)
		(pad "180" smd rect
			(at 2.050034 -33.57499 270)
			(size 0.519938 1.4986)
			(layers "F.Cu" "F.Mask" "F.Paste")
			(net "GND")
		)
		(pad "181" smd rect
			(at 2.050034 -32.725106 270)
			(size 0.519938 1.4986)
			(layers "F.Cu" "F.Mask" "F.Paste")
			(net "M_D_CPU1_SA_DQ<22>")
		)
		(pad "182" smd rect
			(at 2.050034 -31.874968 270)
			(size 0.519938 1.4986)
			(layers "F.Cu" "F.Mask" "F.Paste")
			(net "GND")
		)
		(pad "183" smd rect
			(at 2.050034 -31.025084 270)
			(size 0.519938 1.4986)
			(layers "F.Cu" "F.Mask" "F.Paste")
			(net "M_D_CPU1_SA_DQ<23>")
		)
		(pad "184" smd rect
			(at 2.050034 -30.174946 270)
			(size 0.519938 1.4986)
			(layers "F.Cu" "F.Mask" "F.Paste")
			(net "GND")
		)
		(pad "185" smd rect
			(at 2.050034 -29.325062 270)
			(size 0.519938 1.4986)
			(layers "F.Cu" "F.Mask" "F.Paste")
			(net "M_D_CPU1_SA_DQ<26>")
		)
		(pad "186" smd rect
			(at 2.050034 -28.474924 270)
			(size 0.519938 1.4986)
			(layers "F.Cu" "F.Mask" "F.Paste")
			(net "GND")
		)
		(pad "187" smd rect
			(at 2.050034 -27.62504 270)
			(size 0.519938 1.4986)
			(layers "F.Cu" "F.Mask" "F.Paste")
			(net "M_D_CPU1_SA_DQ<27>")
		)
		(pad "188" smd rect
			(at 2.050034 -26.774902 270)
			(size 0.519938 1.4986)
			(layers "F.Cu" "F.Mask" "F.Paste")
			(net "GND")
		)
		(pad "189" smd rect
			(at 2.050034 -25.925018 270)
			(size 0.519938 1.4986)
			(layers "F.Cu" "F.Mask" "F.Paste")
			(net "M_D_CPU1_SA_DQS_DN<8>")
		)
		(pad "190" smd rect
			(at 2.050034 -25.07488 270)
			(size 0.519938 1.4986)
			(layers "F.Cu" "F.Mask" "F.Paste")
			(net "M_D_CPU1_SA_DQS_DP<8>")
		)
		(pad "191" smd rect
			(at 2.050034 -24.224996 270)
			(size 0.519938 1.4986)
			(layers "F.Cu" "F.Mask" "F.Paste")
			(net "GND")
		)
		(pad "192" smd rect
			(at 2.050034 -23.375112 270)
			(size 0.519938 1.4986)
			(layers "F.Cu" "F.Mask" "F.Paste")
			(net "M_D_CPU1_SA_DQ<30>")
		)
		(pad "193" smd rect
			(at 2.050034 -22.524974 270)
			(size 0.519938 1.4986)
			(layers "F.Cu" "F.Mask" "F.Paste")
			(net "GND")
		)
		(pad "194" smd rect
			(at 2.050034 -21.67509 270)
			(size 0.519938 1.4986)
			(layers "F.Cu" "F.Mask" "F.Paste")
			(net "M_D_CPU1_SA_DQ<31>")
		)
		(pad "195" smd rect
			(at 2.050034 -20.824952 270)
			(size 0.519938 1.4986)
			(layers "F.Cu" "F.Mask" "F.Paste")
			(net "GND")
		)
		(pad "196" smd rect
			(at 2.050034 -19.975068 270)
			(size 0.519938 1.4986)
			(layers "F.Cu" "F.Mask" "F.Paste")
			(net "M_D_CPU1_SA_CB<2>")
		)
		(pad "197" smd rect
			(at 2.050034 -19.12493 270)
			(size 0.519938 1.4986)
			(layers "F.Cu" "F.Mask" "F.Paste")
			(net "GND")
		)
		(pad "198" smd rect
			(at 2.050034 -18.275046 270)
			(size 0.519938 1.4986)
			(layers "F.Cu" "F.Mask" "F.Paste")
			(net "M_D_CPU1_SA_CB<3>")
		)
		(pad "199" smd rect
			(at 2.050034 -17.424908 270)
			(size 0.519938 1.4986)
			(layers "F.Cu" "F.Mask" "F.Paste")
			(net "GND")
		)
		(pad "200" smd rect
			(at 2.050034 -16.575024 270)
			(size 0.519938 1.4986)
			(layers "F.Cu" "F.Mask" "F.Paste")
			(net "M_D_CPU1_SA_DQS_DN<9>")
		)
		(pad "201" smd rect
			(at 2.050034 -15.724886 270)
			(size 0.519938 1.4986)
			(layers "F.Cu" "F.Mask" "F.Paste")
			(net "M_D_CPU1_SA_DQS_DP<9>")
		)
		(pad "202" smd rect
			(at 2.050034 -14.875002 270)
			(size 0.519938 1.4986)
			(layers "F.Cu" "F.Mask" "F.Paste")
			(net "GND")
		)
		(pad "203" smd rect
			(at 2.050034 -14.025118 270)
			(size 0.519938 1.4986)
			(layers "F.Cu" "F.Mask" "F.Paste")
			(net "M_D_CPU1_SA_CB<6>")
		)
		(pad "204" smd rect
			(at 2.050034 -13.17498 270)
			(size 0.519938 1.4986)
			(layers "F.Cu" "F.Mask" "F.Paste")
			(net "GND")
		)
		(pad "205" smd rect
			(at 2.050034 -12.325096 270)
			(size 0.519938 1.4986)
			(layers "F.Cu" "F.Mask" "F.Paste")
			(net "M_D_CPU1_SA_CB<7>")
		)
		(pad "206" smd rect
			(at 2.050034 -11.474958 270)
			(size 0.519938 1.4986)
			(layers "F.Cu" "F.Mask" "F.Paste")
			(net "GND")
		)
		(pad "207" smd rect
			(at 2.050034 -10.625074 270)
			(size 0.519938 1.4986)
			(layers "F.Cu" "F.Mask" "F.Paste")
			(net "RST_M_CD_CPU1_FPGA_N")
		)
		(pad "208" smd rect
			(at 2.050034 -9.774936 270)
			(size 0.519938 1.4986)
			(layers "F.Cu" "F.Mask" "F.Paste")
			(net "GND")
		)
		(pad "209" smd rect
			(at 2.050034 -8.925052 270)
			(size 0.519938 1.4986)
			(layers "F.Cu" "F.Mask" "F.Paste")
			(net "M_D_CPU1_SA_CS_N<3>")
		)
		(pad "210" smd rect
			(at 2.050034 -8.074914 270)
			(size 0.519938 1.4986)
			(layers "F.Cu" "F.Mask" "F.Paste")
			(net "GND")
		)
		(pad "211" smd rect
			(at 2.050034 -7.22503 270)
			(size 0.519938 1.4986)
			(layers "F.Cu" "F.Mask" "F.Paste")
			(net "M_D_CPU1_SA_CA<1>")
		)
		(pad "212" smd rect
			(at 2.050034 -6.374892 270)
			(size 0.519938 1.4986)
			(layers "F.Cu" "F.Mask" "F.Paste")
			(net "GND")
		)
		(pad "213" smd rect
			(at 2.050034 -5.525008 270)
			(size 0.519938 1.4986)
			(layers "F.Cu" "F.Mask" "F.Paste")
			(net "M_D_CPU1_SA_CA<3>")
		)
		(pad "214" smd rect
			(at 2.050034 -4.675124 270)
			(size 0.519938 1.4986)
			(layers "F.Cu" "F.Mask" "F.Paste")
			(net "GND")
		)
		(pad "215" smd rect
			(at 2.050034 -3.824986 270)
			(size 0.519938 1.4986)
			(layers "F.Cu" "F.Mask" "F.Paste")
			(net "M_D_CPU1_SA_CA<5>")
		)
		(pad "216" smd rect
			(at 2.050034 -2.975102 270)
			(size 0.519938 1.4986)
			(layers "F.Cu" "F.Mask" "F.Paste")
			(net "GND")
		)
		(pad "217" smd rect
			(at 2.050034 -2.124964 270)
			(size 0.519938 1.4986)
			(layers "F.Cu" "F.Mask" "F.Paste")
			(net "M_D_CPU1_CLK_DP<1>")
		)
		(pad "218" smd rect
			(at 2.050034 -1.27508 270)
			(size 0.519938 1.4986)
			(layers "F.Cu" "F.Mask" "F.Paste")
			(net "M_D_CPU1_CLK_DN<1>")
		)
		(pad "219" smd rect
			(at 2.050034 -0.424942 270)
			(size 0.519938 1.4986)
			(layers "F.Cu" "F.Mask" "F.Paste")
			(net "GND")
		)
		(pad "220" smd rect
			(at 2.050034 5.525008 270)
			(size 0.519938 1.4986)
			(layers "F.Cu" "F.Mask" "F.Paste")
			(net "TP_CHD_CPU1_DIMM2_FRU_4")
		)
		(pad "221" smd rect
			(at 2.050034 6.374892 270)
			(size 0.519938 1.4986)
			(layers "F.Cu" "F.Mask" "F.Paste")
			(net "M_D_CPU1_SB_CA<1>")
		)
		(pad "222" smd rect
			(at 2.050034 7.22503 270)
			(size 0.519938 1.4986)
			(layers "F.Cu" "F.Mask" "F.Paste")
			(net "GND")
		)
		(pad "223" smd rect
			(at 2.050034 8.074914 270)
			(size 0.519938 1.4986)
			(layers "F.Cu" "F.Mask" "F.Paste")
			(net "M_D_CPU1_SB_CA<3>")
		)
		(pad "224" smd rect
			(at 2.050034 8.925052 270)
			(size 0.519938 1.4986)
			(layers "F.Cu" "F.Mask" "F.Paste")
			(net "GND")
		)
	)
)
